# T6G (Grand Teton) — schematic netlist excerpt (pin names and nets, part order shuffled) for the footprints in the layout excerpt that follows; sources: Cadence DE-HDL packaged netlist, KiCad conversion of 04192023_DAF0TMB3IC0_F0TG_MB_C_brd_V02_OCP.brd

C6507  Q_CAP_DIFFBUS  DIFF BUS_0.22UF 6.3V 20% X6S  pkg C0201  page 275 : \1\ = P5E_CPU0_P0_TX_BUF_C_DP<3> ; \2\ = P5E_CPU0_P0_TX_BUF_DP<3>
R4518  Q_RES  10K 1% CHIP  pkg 0402LF  page 182 : A = FM_9ZXL045_P0_2_OE_N ; B = GND
R8287  Q_RES  1K 1% EMPTY  pkg 0402LF  page 193 : A = PVDD18_S5_P0 ; B = SVID_PVDDCR_CPU0_P0_SVTO

(kicad_pcb
	(version 20260206)
	(generator "pcbnew")
	(generator_version "10.0")
	(general
		(thickness 1.6)
		(legacy_teardrops no)
	)
	(paper "A4")
	(title_block
		(title "04192023_DAF0TMB3IC0_F0TG_MB_C_brd_V02_OCP.brd")
		(comment 1 "Grand Teton / footprints 1291-1293 of 8354")
	)
	(layers
		(0 "F.Cu" signal "TOP")
		(4 "In1.Cu" signal "GND")
		(6 "In2.Cu" signal "IN1")
		(8 "In3.Cu" signal "GND1")
		(10 "In4.Cu" signal "IN2")
		(12 "In5.Cu" signal "GND2")
		(14 "In6.Cu" signal "IN3")
		(16 "In7.Cu" signal "GND3")
		(18 "In8.Cu" signal "VCC")
		(20 "In9.Cu" signal "VCC1")
		(22 "In10.Cu" signal "GND4")
		(24 "In11.Cu" signal "IN4")
		(26 "In12.Cu" signal "GND5")
		(28 "In13.Cu" signal "IN5")
		(30 "In14.Cu" signal "GND6")
		(32 "In15.Cu" signal "IN6")
		(34 "In16.Cu" signal "GND7")
		(2 "B.Cu" signal "BOTTOM")
		(9 "F.Adhes" user "F.Adhesive")
		(11 "B.Adhes" user "B.Adhesive")
		(13 "F.Paste" user "Package Geometry/Pastemask Top")
		(15 "B.Paste" user "Package Geometry/Pastemask Bottom")
		(5 "F.SilkS" user "Ref Des/Silkscreen Top")
		(7 "B.SilkS" user "Ref Des/Silkscreen Bottom")
		(1 "F.Mask" user "Board Geometry/Soldermask Top")
		(3 "B.Mask" user "Board Geometry/Soldermask Bottom")
		(17 "Dwgs.User" user "User.Drawings")
		(19 "Cmts.User" user "User.Comments")
		(21 "Eco1.User" user "User.Eco1")
		(23 "Eco2.User" user "User.Eco2")
		(25 "Edge.Cuts" user "Board Geometry/Outline")
		(27 "Margin" user)
		(31 "F.CrtYd" user "Package Geometry/Place Bound Top")
		(29 "B.CrtYd" user "Package Geometry/Place Bound Bottom")
		(35 "F.Fab" user "Ref Des/Assembly Top")
		(33 "B.Fab" user "Ref Des/Assembly Bottom")
	)
	(footprint ""
		(layer "F.Cu")
		(at 290.603178 -423.434764 90)
		(property "Reference" "R4518"
			(at 0 0 90)
			(layer "F.SilkS")
			(hide yes)
			(effects
				(font
					(size 1.27 1.27)
				)
			)
		)
		(property "Value" ""
			(at 0 0 90)
			(layer "F.Fab")
			(effects
				(font
					(size 1.27 1.27)
				)
			)
		)
		(duplicate_pad_numbers_are_jumpers no)
		(fp_line
			(start 0.7874 -0.4064)
			(end 0.7874 0.4064)
			(stroke
				(width 0.1524)
				(type default)
			)
			(layer "F.SilkS")
		)
		(fp_line
			(start -0.7874 -0.4064)
			(end 0.7874 -0.4064)
			(stroke
				(width 0.1524)
				(type default)
			)
			(layer "F.SilkS")
		)
		(fp_line
			(start 0.7874 0.4064)
			(end -0.7874 0.4064)
			(stroke
				(width 0.1524)
				(type default)
			)
			(layer "F.SilkS")
		)
		(fp_line
			(start -0.7874 0.4064)
			(end -0.7874 -0.4064)
			(stroke
				(width 0.1524)
				(type default)
			)
			(layer "F.SilkS")
		)
		(fp_line
			(start -0.12065 -0.305054)
			(end -0.12065 -0.2794)
			(stroke
				(width 0.1)
				(type default)
			)
			(layer "F.Fab")
		)
		(fp_line
			(start -0.67945 -0.305054)
			(end -0.12065 -0.305054)
			(stroke
				(width 0.1)
				(type default)
			)
			(layer "F.Fab")
		)
		(fp_line
			(start 0.67945 -0.3048)
			(end 0.67945 0.3048)
			(stroke
				(width 0.1)
				(type default)
			)
			(layer "F.Fab")
		)
		(fp_line
			(start 0.12065 -0.3048)
			(end 0.67945 -0.3048)
			(stroke
				(width 0.1)
				(type default)
			)
			(layer "F.Fab")
		)
		(fp_line
			(start 0.12065 -0.2794)
			(end 0.12065 -0.3048)
			(stroke
				(width 0.1)
				(type default)
			)
			(layer "F.Fab")
		)
		(fp_line
			(start -0.12065 -0.2794)
			(end 0.12065 -0.2794)
			(stroke
				(width 0.1)
				(type default)
			)
			(layer "F.Fab")
		)
		(fp_line
			(start 0.120396 0.2794)
			(end -0.12065 0.2794)
			(stroke
				(width 0.1)
				(type default)
			)
			(layer "F.Fab")
		)
		(fp_line
			(start -0.12065 0.2794)
			(end -0.12065 0.3048)
			(stroke
				(width 0.1)
				(type default)
			)
			(layer "F.Fab")
		)
		(fp_line
			(start 0.67945 0.3048)
			(end 0.120396 0.3048)
			(stroke
				(width 0.1)
				(type default)
			)
			(layer "F.Fab")
		)
		(fp_line
			(start 0.120396 0.3048)
			(end 0.120396 0.2794)
			(stroke
				(width 0.1)
				(type default)
			)
			(layer "F.Fab")
		)
		(fp_line
			(start -0.12065 0.3048)
			(end -0.67945 0.3048)
			(stroke
				(width 0.1)
				(type default)
			)
			(layer "F.Fab")
		)
		(fp_line
			(start -0.67945 0.3048)
			(end -0.67945 -0.305054)
			(stroke
				(width 0.1)
				(type default)
			)
			(layer "F.Fab")
		)
		(pad "1" smd circle
			(at -0.40005 0 90)
			(size 0 0)
			(layers "F.Cu" "F.Mask" "F.Paste")
			(net "FM_9ZXL045_P0_2_OE_N")
		)
		(pad "2" smd circle
			(at 0.40005 0 90)
			(size 0 0)
			(layers "F.Cu" "F.Mask" "F.Paste")
			(net "GND")
		)
	)
	(footprint ""
		(layer "F.Cu")
		(at 313.872626 -416.899344 -90)
		(property "Reference" "C6507"
			(at 0 0 270)
			(layer "F.SilkS")
			(hide yes)
			(effects
				(font
					(size 1.27 1.27)
				)
			)
		)
		(property "Value" ""
			(at 0 0 270)
			(layer "F.Fab")
			(effects
				(font
					(size 1.27 1.27)
				)
			)
		)
		(duplicate_pad_numbers_are_jumpers no)
		(fp_line
			(start -0.299974 0.150114)
			(end -0.299974 -0.150114)
			(stroke
				(width 0.1)
				(type default)
			)
			(layer "F.Fab")
		)
		(fp_line
			(start 0.299974 0.150114)
			(end -0.299974 0.150114)
			(stroke
				(width 0.1)
				(type default)
			)
			(layer "F.Fab")
		)
		(fp_line
			(start -0.299974 -0.150114)
			(end 0.299974 -0.150114)
			(stroke
				(width 0.1)
				(type default)
			)
			(layer "F.Fab")
		)
		(fp_line
			(start 0.299974 -0.150114)
			(end 0.299974 0.150114)
			(stroke
				(width 0.1)
				(type default)
			)
			(layer "F.Fab")
		)
		(pad "1" smd rect
			(at -0.2667 0 270)
			(size 0.3048 0.381)
			(layers "F.Cu" "F.Mask" "F.Paste")
			(net "P5E_CPU0_P0_TX_BUF_C_DP<3>")
		)
		(pad "2" smd rect
			(at 0.2667 0 270)
			(size 0.3048 0.381)
			(layers "F.Cu" "F.Mask" "F.Paste")
			(net "P5E_CPU0_P0_TX_BUF_DP<3>")
		)
	)
	(footprint ""
		(layer "F.Cu")
		(at 372.937278 -146.552158 180)
		(property "Reference" "R8287"
			(at 0 0 180)
			(layer "F.SilkS")
			(hide yes)
			(effects
				(font
					(size 1.27 1.27)
				)
			)
		)
		(property "Value" ""
			(at 0 0 180)
			(layer "F.Fab")
			(effects
				(font
					(size 1.27 1.27)
				)
			)
		)
		(duplicate_pad_numbers_are_jumpers no)
		(fp_line
			(start 0.7874 0.4064)
			(end -0.7874 0.4064)
			(stroke
				(width 0.1524)
				(type default)
			)
			(layer "F.SilkS")
		)
		(fp_line
			(start 0.7874 -0.4064)
			(end 0.7874 0.4064)
			(stroke
				(width 0.1524)
				(type default)
			)
			(layer "F.SilkS")
		)
		(fp_line
			(start -0.7874 0.4064)
			(end -0.7874 -0.4064)
			(stroke
				(width 0.1524)
				(type default)
			)
			(layer "F.SilkS")
		)
		(fp_line
			(start -0.7874 -0.4064)
			(end 0.7874 -0.4064)
			(stroke
				(width 0.1524)
				(type default)
			)
			(layer "F.SilkS")
		)
		(fp_line
			(start 0.67945 0.3048)
			(end 0.120396 0.3048)
			(stroke
				(width 0.1)
				(type default)
			)
			(layer "F.Fab")
		)
		(fp_line
			(start 0.67945 -0.3048)
			(end 0.67945 0.3048)
			(stroke
				(width 0.1)
				(type default)
			)
			(layer "F.Fab")
		)
		(fp_line
			(start 0.12065 -0.2794)
			(end 0.12065 -0.3048)
			(stroke
				(width 0.1)
				(type default)
			)
			(layer "F.Fab")
		)
		(fp_line
			(start 0.12065 -0.3048)
			(end 0.67945 -0.3048)
			(stroke
				(width 0.1)
				(type default)
			)
			(layer "F.Fab")
		)
		(fp_line
			(start 0.120396 0.3048)
			(end 0.120396 0.2794)
			(stroke
				(width 0.1)
				(type default)
			)
			(layer "F.Fab")
		)
		(fp_line
			(start 0.120396 0.2794)
			(end -0.12065 0.2794)
			(stroke
				(width 0.1)
				(type default)
			)
			(layer "F.Fab")
		)
		(fp_line
			(start -0.12065 0.3048)
			(end -0.67945 0.3048)
			(stroke
				(width 0.1)
				(type default)
			)
			(layer "F.Fab")
		)
		(fp_line
			(start -0.12065 0.2794)
			(end -0.12065 0.3048)
			(stroke
				(width 0.1)
				(type default)
			)
			(layer "F.Fab")
		)
		(fp_line
			(start -0.12065 -0.2794)
			(end 0.12065 -0.2794)
			(stroke
				(width 0.1)
				(type default)
			)
			(layer "F.Fab")
		)
		(fp_line
			(start -0.12065 -0.305054)
			(end -0.12065 -0.2794)
			(stroke
				(width 0.1)
				(type default)
			)
			(layer "F.Fab")
		)
		(fp_line
			(start -0.67945 0.3048)
			(end -0.67945 -0.305054)
			(stroke
				(width 0.1)
				(type default)
			)
			(layer "F.Fab")
		)
		(fp_line
			(start -0.67945 -0.305054)
			(end -0.12065 -0.305054)
			(stroke
				(width 0.1)
				(type default)
			)
			(layer "F.Fab")
		)
		(pad "1" smd circle
			(at -0.40005 0 180)
			(size 0 0)
			(layers "F.Cu" "F.Mask" "F.Paste")
			(net "PVDD18_S5_P0")
		)
		(pad "2" smd circle
			(at 0.40005 0 180)
			(size 0 0)
			(layers "F.Cu" "F.Mask" "F.Paste")
			(net "SVID_PVDDCR_CPU0_P0_SVTO")
		)
	)
)
